# S9S_MB_2U (Grand Teton) — schematic netlist excerpt (pin names and nets, part order shuffled) for the footprints in the layout excerpt that follows; sources: Cadence DE-HDL packaged netlist, KiCad conversion of 03242023_DA0F0TMBIJ0_F0T_Motherboard_J_brd_V01_OCP.brd

PC1356  Q_CAP  0.1UF 25V 10% X7R  pkg 0402  page 267 : A = GND ; B = PVCCIN_CPU0_VREF

(kicad_pcb
	(version 20260206)
	(generator "pcbnew")
	(generator_version "10.0")
	(general
		(thickness 1.6)
		(legacy_teardrops no)
	)
	(paper "A4")
	(title_block
		(title "03242023_DA0F0TMBIJ0_F0T_Motherboard_J_brd_V01_OCP.brd")
		(comment 1 "Grand Teton / footprints 246-246 of 6105")
	)
	(layers
		(0 "F.Cu" signal "TOP")
		(4 "In1.Cu" signal "GND")
		(6 "In2.Cu" signal "IN1")
		(8 "In3.Cu" signal "GND1")
		(10 "In4.Cu" signal "IN2")
		(12 "In5.Cu" signal "GND2")
		(14 "In6.Cu" signal "IN3")
		(16 "In7.Cu" signal "GND3")
		(18 "In8.Cu" signal "VCC")
		(20 "In9.Cu" signal "VCC1")
		(22 "In10.Cu" signal "GND4")
		(24 "In11.Cu" signal "IN4")
		(26 "In12.Cu" signal "GND5")
		(28 "In13.Cu" signal "IN5")
		(30 "In14.Cu" signal "GND6")
		(32 "In15.Cu" signal "IN6")
		(34 "In16.Cu" signal "GND7")
		(2 "B.Cu" signal "BOTTOM")
		(9 "F.Adhes" user "F.Adhesive")
		(11 "B.Adhes" user "B.Adhesive")
		(13 "F.Paste" user "Package Geometry/Pastemask Top")
		(15 "B.Paste" user "Package Geometry/Pastemask Bottom")
		(5 "F.SilkS" user "Ref Des/Silkscreen Top")
		(7 "B.SilkS" user "Ref Des/Silkscreen Bottom")
		(1 "F.Mask" user "Board Geometry/Soldermask Top")
		(3 "B.Mask" user "Board Geometry/Soldermask Bottom")
		(17 "Dwgs.User" user "User.Drawings")
		(19 "Cmts.User" user "User.Comments")
		(21 "Eco1.User" user "User.Eco1")
		(23 "Eco2.User" user "User.Eco2")
		(25 "Edge.Cuts" user "Board Geometry/Outline")
		(27 "Margin" user)
		(31 "F.CrtYd" user "Package Geometry/Place Bound Top")
		(29 "B.CrtYd" user "Package Geometry/Place Bound Bottom")
		(35 "F.Fab" user "Ref Des/Assembly Top")
		(33 "B.Fab" user "Ref Des/Assembly Bottom")
	)
	(footprint ""
		(layer "F.Cu")
		(at 342.14181 -338.298282 -90)
		(property "Reference" "PC1356"
			(at 0 0 270)
			(layer "F.SilkS")
			(hide yes)
			(effects
				(font
					(size 1.27 1.27)
				)
			)
		)
		(property "Value" ""
			(at 0 0 270)
			(layer "F.Fab")
			(effects
				(font
					(size 1.27 1.27)
				)
			)
		)
		(duplicate_pad_numbers_are_jumpers no)
		(fp_line
			(start -0.7874 0.4064)
			(end -0.7874 -0.4064)
			(stroke
				(width 0.1524)
				(type default)
			)
			(layer "F.SilkS")
		)
		(fp_line
			(start 0.7874 0.4064)
			(end -0.7874 0.4064)
			(stroke
				(width 0.1524)
				(type default)
			)
			(layer "F.SilkS")
		)
		(fp_line
			(start -0.7874 -0.4064)
			(end 0.7874 -0.4064)
			(stroke
				(width 0.1524)
				(type default)
			)
			(layer "F.SilkS")
		)
		(fp_line
			(start 0.7874 -0.4064)
			(end 0.7874 0.4064)
			(stroke
				(width 0.1524)
				(type default)
			)
			(layer "F.SilkS")
		)
		(fp_line
			(start -0.67945 0.3048)
			(end -0.67945 -0.305054)
			(stroke
				(width 0.1)
				(type default)
			)
			(layer "F.Fab")
		)
		(fp_line
			(start -0.12065 0.3048)
			(end -0.67945 0.3048)
			(stroke
				(width 0.1)
				(type default)
			)
			(layer "F.Fab")
		)
		(fp_line
			(start 0.120396 0.3048)
			(end 0.120396 0.2794)
			(stroke
				(width 0.1)
				(type default)
			)
			(layer "F.Fab")
		)
		(fp_line
			(start 0.67945 0.3048)
			(end 0.120396 0.3048)
			(stroke
				(width 0.1)
				(type default)
			)
			(layer "F.Fab")
		)
		(fp_line
			(start -0.12065 0.2794)
			(end -0.12065 0.3048)
			(stroke
				(width 0.1)
				(type default)
			)
			(layer "F.Fab")
		)
		(fp_line
			(start 0.120396 0.2794)
			(end -0.12065 0.2794)
			(stroke
				(width 0.1)
				(type default)
			)
			(layer "F.Fab")
		)
		(fp_line
			(start -0.12065 -0.2794)
			(end 0.12065 -0.2794)
			(stroke
				(width 0.1)
				(type default)
			)
			(layer "F.Fab")
		)
		(fp_line
			(start 0.12065 -0.2794)
			(end 0.12065 -0.3048)
			(stroke
				(width 0.1)
				(type default)
			)
			(layer "F.Fab")
		)
		(fp_line
			(start 0.12065 -0.3048)
			(end 0.67945 -0.3048)
			(stroke
				(width 0.1)
				(type default)
			)
			(layer "F.Fab")
		)
		(fp_line
			(start 0.67945 -0.3048)
			(end 0.67945 0.3048)
			(stroke
				(width 0.1)
				(type default)
			)
			(layer "F.Fab")
		)
		(fp_line
			(start -0.67945 -0.305054)
			(end -0.12065 -0.305054)
			(stroke
				(width 0.1)
				(type default)
			)
			(layer "F.Fab")
		)
		(fp_line
			(start -0.12065 -0.305054)
			(end -0.12065 -0.2794)
			(stroke
				(width 0.1)
				(type default)
			)
			(layer "F.Fab")
		)
		(pad "1" smd circle
			(at -0.40005 0 270)
			(size 0 0)
			(layers "F.Cu" "F.Mask" "F.Paste")
			(net "GND")
		)
		(pad "2" smd circle
			(at 0.40005 0 270)
			(size 0 0)
			(layers "F.Cu" "F.Mask" "F.Paste")
			(net "PVCCIN_CPU0_VREF")
		)
	)
)
